# S9S_MB_2U (Grand Teton) — schematic netlist excerpt (pin names and nets, part order shuffled) for the footprints in the layout excerpt that follows; sources: Cadence DE-HDL packaged netlist, KiCad conversion of 03242023_DA0F0TMBIJ0_F0T_Motherboard_J_brd_V01_OCP.brd

C498  Q_CAP  47UF 4V 20% X6S  pkg C0805  page 76 : A = PVCCFA_EHV_FIVRA_CPU0 ; B = GND
R1473  Q_RES  1K 1% CHIP  pkg 0402LF  page 220 : A = FM_RST_PERST_BIT1 ; B = P3V3_AUX
PC1600  Q_CAP  22UF 10V 20% X6S  pkg C0805  page 259 : A = P3V3_AUX ; B = GND

(kicad_pcb
	(version 20260206)
	(generator "pcbnew")
	(generator_version "10.0")
	(general
		(thickness 1.6)
		(legacy_teardrops no)
	)
	(paper "A4")
	(title_block
		(title "03242023_DA0F0TMBIJ0_F0T_Motherboard_J_brd_V01_OCP.brd")
		(comment 1 "Grand Teton / footprints 5565-5567 of 6105")
	)
	(layers
		(0 "F.Cu" signal "TOP")
		(4 "In1.Cu" signal "GND")
		(6 "In2.Cu" signal "IN1")
		(8 "In3.Cu" signal "GND1")
		(10 "In4.Cu" signal "IN2")
		(12 "In5.Cu" signal "GND2")
		(14 "In6.Cu" signal "IN3")
		(16 "In7.Cu" signal "GND3")
		(18 "In8.Cu" signal "VCC")
		(20 "In9.Cu" signal "VCC1")
		(22 "In10.Cu" signal "GND4")
		(24 "In11.Cu" signal "IN4")
		(26 "In12.Cu" signal "GND5")
		(28 "In13.Cu" signal "IN5")
		(30 "In14.Cu" signal "GND6")
		(32 "In15.Cu" signal "IN6")
		(34 "In16.Cu" signal "GND7")
		(2 "B.Cu" signal "BOTTOM")
		(9 "F.Adhes" user "F.Adhesive")
		(11 "B.Adhes" user "B.Adhesive")
		(13 "F.Paste" user "Package Geometry/Pastemask Top")
		(15 "B.Paste" user "Package Geometry/Pastemask Bottom")
		(5 "F.SilkS" user "Ref Des/Silkscreen Top")
		(7 "B.SilkS" user "Ref Des/Silkscreen Bottom")
		(1 "F.Mask" user "Board Geometry/Soldermask Top")
		(3 "B.Mask" user "Board Geometry/Soldermask Bottom")
		(17 "Dwgs.User" user "User.Drawings")
		(19 "Cmts.User" user "User.Comments")
		(21 "Eco1.User" user "User.Eco1")
		(23 "Eco2.User" user "User.Eco2")
		(25 "Edge.Cuts" user "Board Geometry/Outline")
		(27 "Margin" user)
		(31 "F.CrtYd" user "Package Geometry/Place Bound Top")
		(29 "B.CrtYd" user "Package Geometry/Place Bound Bottom")
		(35 "F.Fab" user "Ref Des/Assembly Top")
		(33 "B.Fab" user "Ref Des/Assembly Bottom")
	)
	(footprint ""
		(layer "B.Cu")
		(at 408.807158 -258.318254 -90)
		(property "Reference" "C498"
			(at 0 0 90)
			(layer "B.SilkS")
			(hide yes)
			(effects
				(font
					(size 1.27 1.27)
				)
				(justify mirror)
			)
		)
		(property "Value" ""
			(at 0 0 90)
			(layer "B.Fab")
			(effects
				(font
					(size 1.27 1.27)
				)
				(justify mirror)
			)
		)
		(duplicate_pad_numbers_are_jumpers no)
		(fp_line
			(start -1.524 0.762)
			(end 1.524 0.762)
			(stroke
				(width 0.1524)
				(type default)
			)
			(layer "B.SilkS")
		)
		(fp_line
			(start 1.524 0.762)
			(end 1.524 -0.762)
			(stroke
				(width 0.1524)
				(type default)
			)
			(layer "B.SilkS")
		)
		(fp_line
			(start -1.524 -0.762)
			(end -1.524 0.762)
			(stroke
				(width 0.1524)
				(type default)
			)
			(layer "B.SilkS")
		)
		(fp_line
			(start 1.524 -0.762)
			(end -1.524 -0.762)
			(stroke
				(width 0.1524)
				(type default)
			)
			(layer "B.SilkS")
		)
		(fp_line
			(start -1.1049 0.724916)
			(end -1.1049 -0.724916)
			(stroke
				(width 0.1)
				(type default)
			)
			(layer "B.Fab")
		)
		(fp_line
			(start 1.1049 0.724916)
			(end -1.1049 0.724916)
			(stroke
				(width 0.1)
				(type default)
			)
			(layer "B.Fab")
		)
		(fp_line
			(start -1.1049 -0.724916)
			(end 1.1049 -0.724916)
			(stroke
				(width 0.1)
				(type default)
			)
			(layer "B.Fab")
		)
		(fp_line
			(start 1.1049 -0.724916)
			(end 1.1049 0.724916)
			(stroke
				(width 0.1)
				(type default)
			)
			(layer "B.Fab")
		)
		(pad "1" smd rect
			(at 0.889 0 270)
			(size 1.016 1.27)
			(layers "B.Cu" "B.Mask" "B.Paste")
			(net "PVCCFA_EHV_FIVRA_CPU0")
		)
		(pad "2" smd rect
			(at -0.889 0 270)
			(size 1.016 1.27)
			(layers "B.Cu" "B.Mask" "B.Paste")
			(net "GND")
		)
	)
	(footprint ""
		(layer "B.Cu")
		(at 190.80988 -130.266948 -90)
		(property "Reference" "R1473"
			(at 0 0 90)
			(layer "B.SilkS")
			(hide yes)
			(effects
				(font
					(size 1.27 1.27)
				)
				(justify mirror)
			)
		)
		(property "Value" ""
			(at 0 0 90)
			(layer "B.Fab")
			(effects
				(font
					(size 1.27 1.27)
				)
				(justify mirror)
			)
		)
		(duplicate_pad_numbers_are_jumpers no)
		(fp_line
			(start -0.7874 0.4064)
			(end 0.7874 0.4064)
			(stroke
				(width 0.1524)
				(type default)
			)
			(layer "B.SilkS")
		)
		(fp_line
			(start 0.7874 0.4064)
			(end 0.7874 -0.4064)
			(stroke
				(width 0.1524)
				(type default)
			)
			(layer "B.SilkS")
		)
		(fp_line
			(start -0.7874 -0.4064)
			(end -0.7874 0.4064)
			(stroke
				(width 0.1524)
				(type default)
			)
			(layer "B.SilkS")
		)
		(fp_line
			(start 0.7874 -0.4064)
			(end -0.7874 -0.4064)
			(stroke
				(width 0.1524)
				(type default)
			)
			(layer "B.SilkS")
		)
		(fp_line
			(start -0.67945 0.3048)
			(end -0.120396 0.3048)
			(stroke
				(width 0.1)
				(type default)
			)
			(layer "B.Fab")
		)
		(fp_line
			(start -0.120396 0.3048)
			(end -0.120396 0.2794)
			(stroke
				(width 0.1)
				(type default)
			)
			(layer "B.Fab")
		)
		(fp_line
			(start 0.12065 0.3048)
			(end 0.67945 0.3048)
			(stroke
				(width 0.1)
				(type default)
			)
			(layer "B.Fab")
		)
		(fp_line
			(start 0.67945 0.3048)
			(end 0.67945 -0.305054)
			(stroke
				(width 0.1)
				(type default)
			)
			(layer "B.Fab")
		)
		(fp_line
			(start -0.120396 0.2794)
			(end 0.12065 0.2794)
			(stroke
				(width 0.1)
				(type default)
			)
			(layer "B.Fab")
		)
		(fp_line
			(start 0.12065 0.2794)
			(end 0.12065 0.3048)
			(stroke
				(width 0.1)
				(type default)
			)
			(layer "B.Fab")
		)
		(fp_line
			(start -0.12065 -0.2794)
			(end -0.12065 -0.3048)
			(stroke
				(width 0.1)
				(type default)
			)
			(layer "B.Fab")
		)
		(fp_line
			(start 0.12065 -0.2794)
			(end -0.12065 -0.2794)
			(stroke
				(width 0.1)
				(type default)
			)
			(layer "B.Fab")
		)
		(fp_line
			(start -0.67945 -0.3048)
			(end -0.67945 0.3048)
			(stroke
				(width 0.1)
				(type default)
			)
			(layer "B.Fab")
		)
		(fp_line
			(start -0.12065 -0.3048)
			(end -0.67945 -0.3048)
			(stroke
				(width 0.1)
				(type default)
			)
			(layer "B.Fab")
		)
		(fp_line
			(start 0.12065 -0.305054)
			(end 0.12065 -0.2794)
			(stroke
				(width 0.1)
				(type default)
			)
			(layer "B.Fab")
		)
		(fp_line
			(start 0.67945 -0.305054)
			(end 0.12065 -0.305054)
			(stroke
				(width 0.1)
				(type default)
			)
			(layer "B.Fab")
		)
		(pad "1" smd circle
			(at 0.40005 0 90)
			(size 0 0)
			(layers "B.Cu" "B.Mask" "B.Paste")
			(net "FM_RST_PERST_BIT1")
		)
		(pad "2" smd circle
			(at -0.40005 0 90)
			(size 0 0)
			(layers "B.Cu" "B.Mask" "B.Paste")
			(net "P3V3_AUX")
		)
	)
	(footprint ""
		(layer "B.Cu")
		(at 447.771012 -58.325512 -90)
		(property "Reference" "PC1600"
			(at 0 0 90)
			(layer "B.SilkS")
			(hide yes)
			(effects
				(font
					(size 1.27 1.27)
				)
				(justify mirror)
			)
		)
		(property "Value" ""
			(at 0 0 90)
			(layer "B.Fab")
			(effects
				(font
					(size 1.27 1.27)
				)
				(justify mirror)
			)
		)
		(duplicate_pad_numbers_are_jumpers no)
		(fp_line
			(start -1.524 0.762)
			(end 1.524 0.762)
			(stroke
				(width 0.1524)
				(type default)
			)
			(layer "B.SilkS")
		)
		(fp_line
			(start 1.524 0.762)
			(end 1.524 -0.762)
			(stroke
				(width 0.1524)
				(type default)
			)
			(layer "B.SilkS")
		)
		(fp_line
			(start -1.524 -0.762)
			(end -1.524 0.762)
			(stroke
				(width 0.1524)
				(type default)
			)
			(layer "B.SilkS")
		)
		(fp_line
			(start 1.524 -0.762)
			(end -1.524 -0.762)
			(stroke
				(width 0.1524)
				(type default)
			)
			(layer "B.SilkS")
		)
		(fp_line
			(start -1.1049 0.724916)
			(end -1.1049 -0.724916)
			(stroke
				(width 0.1)
				(type default)
			)
			(layer "B.Fab")
		)
		(fp_line
			(start 1.1049 0.724916)
			(end -1.1049 0.724916)
			(stroke
				(width 0.1)
				(type default)
			)
			(layer "B.Fab")
		)
		(fp_line
			(start -1.1049 -0.724916)
			(end 1.1049 -0.724916)
			(stroke
				(width 0.1)
				(type default)
			)
			(layer "B.Fab")
		)
		(fp_line
			(start 1.1049 -0.724916)
			(end 1.1049 0.724916)
			(stroke
				(width 0.1)
				(type default)
			)
			(layer "B.Fab")
		)
		(pad "1" smd rect
			(at 0.889 0 270)
			(size 1.016 1.27)
			(layers "B.Cu" "B.Mask" "B.Paste")
			(net "P3V3_AUX")
		)
		(pad "2" smd rect
			(at -0.889 0 270)
			(size 1.016 1.27)
			(layers "B.Cu" "B.Mask" "B.Paste")
			(net "GND")
		)
	)
)
